# T6G (Grand Teton) — schematic netlist excerpt (pin names and nets, part order shuffled) for the footprints in the layout excerpt that follows; sources: Cadence DE-HDL packaged netlist, KiCad conversion of 04192023_DAF0TMB3IC0_F0TG_MB_C_brd_V02_OCP.brd

R1224  Q_RES  4.7K 1% CHIP  pkg 0402LF  page 258 : A = PVDD_33_S5_ADC ; B = GND
C314  Q_CAP  1UF 4V 20% X6S  pkg 0201  page 334 : A = P0V9_CPU1_RT1_2A ; B = GND
C2202  Q_CAP  22UF 4V 20% X6S  pkg C0402  page 69 : A = PVDDCR_CPU1_P0 ; B = GND

(kicad_pcb
	(version 20260206)
	(generator "pcbnew")
	(generator_version "10.0")
	(general
		(thickness 1.6)
		(legacy_teardrops no)
	)
	(paper "A4")
	(title_block
		(title "04192023_DAF0TMB3IC0_F0TG_MB_C_brd_V02_OCP.brd")
		(comment 1 "Grand Teton / footprints 6516-6518 of 8354")
	)
	(layers
		(0 "F.Cu" signal "TOP")
		(4 "In1.Cu" signal "GND")
		(6 "In2.Cu" signal "IN1")
		(8 "In3.Cu" signal "GND1")
		(10 "In4.Cu" signal "IN2")
		(12 "In5.Cu" signal "GND2")
		(14 "In6.Cu" signal "IN3")
		(16 "In7.Cu" signal "GND3")
		(18 "In8.Cu" signal "VCC")
		(20 "In9.Cu" signal "VCC1")
		(22 "In10.Cu" signal "GND4")
		(24 "In11.Cu" signal "IN4")
		(26 "In12.Cu" signal "GND5")
		(28 "In13.Cu" signal "IN5")
		(30 "In14.Cu" signal "GND6")
		(32 "In15.Cu" signal "IN6")
		(34 "In16.Cu" signal "GND7")
		(2 "B.Cu" signal "BOTTOM")
		(9 "F.Adhes" user "F.Adhesive")
		(11 "B.Adhes" user "B.Adhesive")
		(13 "F.Paste" user "Package Geometry/Pastemask Top")
		(15 "B.Paste" user "Package Geometry/Pastemask Bottom")
		(5 "F.SilkS" user "Ref Des/Silkscreen Top")
		(7 "B.SilkS" user "Ref Des/Silkscreen Bottom")
		(1 "F.Mask" user "Board Geometry/Soldermask Top")
		(3 "B.Mask" user "Board Geometry/Soldermask Bottom")
		(17 "Dwgs.User" user "User.Drawings")
		(19 "Cmts.User" user "User.Comments")
		(21 "Eco1.User" user "User.Eco1")
		(23 "Eco2.User" user "User.Eco2")
		(25 "Edge.Cuts" user "Board Geometry/Outline")
		(27 "Margin" user)
		(31 "F.CrtYd" user "Package Geometry/Place Bound Top")
		(29 "B.CrtYd" user "Package Geometry/Place Bound Bottom")
		(35 "F.Fab" user "Ref Des/Assembly Top")
		(33 "B.Fab" user "Ref Des/Assembly Bottom")
	)
	(footprint ""
		(layer "B.Cu")
		(at 361.973114 -267.52931)
		(property "Reference" "C2202"
			(at 0 0 0)
			(layer "B.SilkS")
			(hide yes)
			(effects
				(font
					(size 1.27 1.27)
				)
				(justify mirror)
			)
		)
		(property "Value" ""
			(at 0 0 0)
			(layer "B.Fab")
			(effects
				(font
					(size 1.27 1.27)
				)
				(justify mirror)
			)
		)
		(duplicate_pad_numbers_are_jumpers no)
		(fp_line
			(start -0.7874 -0.4064)
			(end -0.7874 0.4064)
			(stroke
				(width 0.1524)
				(type default)
			)
			(layer "B.SilkS")
		)
		(fp_line
			(start -0.7874 0.4064)
			(end 0.7874 0.4064)
			(stroke
				(width 0.1524)
				(type default)
			)
			(layer "B.SilkS")
		)
		(fp_line
			(start 0.7874 -0.4064)
			(end -0.7874 -0.4064)
			(stroke
				(width 0.1524)
				(type default)
			)
			(layer "B.SilkS")
		)
		(fp_line
			(start 0.7874 0.4064)
			(end 0.7874 -0.4064)
			(stroke
				(width 0.1524)
				(type default)
			)
			(layer "B.SilkS")
		)
		(fp_line
			(start -0.67945 -0.3048)
			(end -0.67945 0.3048)
			(stroke
				(width 0.1)
				(type default)
			)
			(layer "B.Fab")
		)
		(fp_line
			(start -0.67945 0.3048)
			(end -0.120396 0.3048)
			(stroke
				(width 0.1)
				(type default)
			)
			(layer "B.Fab")
		)
		(fp_line
			(start -0.12065 -0.3048)
			(end -0.67945 -0.3048)
			(stroke
				(width 0.1)
				(type default)
			)
			(layer "B.Fab")
		)
		(fp_line
			(start -0.12065 -0.2794)
			(end -0.12065 -0.3048)
			(stroke
				(width 0.1)
				(type default)
			)
			(layer "B.Fab")
		)
		(fp_line
			(start -0.120396 0.2794)
			(end 0.12065 0.2794)
			(stroke
				(width 0.1)
				(type default)
			)
			(layer "B.Fab")
		)
		(fp_line
			(start -0.120396 0.3048)
			(end -0.120396 0.2794)
			(stroke
				(width 0.1)
				(type default)
			)
			(layer "B.Fab")
		)
		(fp_line
			(start 0.12065 -0.305054)
			(end 0.12065 -0.2794)
			(stroke
				(width 0.1)
				(type default)
			)
			(layer "B.Fab")
		)
		(fp_line
			(start 0.12065 -0.2794)
			(end -0.12065 -0.2794)
			(stroke
				(width 0.1)
				(type default)
			)
			(layer "B.Fab")
		)
		(fp_line
			(start 0.12065 0.2794)
			(end 0.12065 0.3048)
			(stroke
				(width 0.1)
				(type default)
			)
			(layer "B.Fab")
		)
		(fp_line
			(start 0.12065 0.3048)
			(end 0.67945 0.3048)
			(stroke
				(width 0.1)
				(type default)
			)
			(layer "B.Fab")
		)
		(fp_line
			(start 0.67945 -0.305054)
			(end 0.12065 -0.305054)
			(stroke
				(width 0.1)
				(type default)
			)
			(layer "B.Fab")
		)
		(fp_line
			(start 0.67945 0.3048)
			(end 0.67945 -0.305054)
			(stroke
				(width 0.1)
				(type default)
			)
			(layer "B.Fab")
		)
		(pad "1" smd circle
			(at 0.40005 0 180)
			(size 0 0)
			(layers "B.Cu" "B.Mask" "B.Paste")
			(net "PVDDCR_CPU1_P0")
		)
		(pad "2" smd circle
			(at -0.40005 0 180)
			(size 0 0)
			(layers "B.Cu" "B.Mask" "B.Paste")
			(net "GND")
		)
	)
	(footprint ""
		(layer "B.Cu")
		(at 234.830874 -326.947022 180)
		(property "Reference" "R1224"
			(at 0 0 0)
			(layer "B.SilkS")
			(hide yes)
			(effects
				(font
					(size 1.27 1.27)
				)
				(justify mirror)
			)
		)
		(property "Value" ""
			(at 0 0 0)
			(layer "B.Fab")
			(effects
				(font
					(size 1.27 1.27)
				)
				(justify mirror)
			)
		)
		(duplicate_pad_numbers_are_jumpers no)
		(fp_line
			(start 0.7874 0.4064)
			(end 0.7874 -0.4064)
			(stroke
				(width 0.1524)
				(type default)
			)
			(layer "B.SilkS")
		)
		(fp_line
			(start 0.7874 -0.4064)
			(end -0.7874 -0.4064)
			(stroke
				(width 0.1524)
				(type default)
			)
			(layer "B.SilkS")
		)
		(fp_line
			(start -0.7874 0.4064)
			(end 0.7874 0.4064)
			(stroke
				(width 0.1524)
				(type default)
			)
			(layer "B.SilkS")
		)
		(fp_line
			(start -0.7874 -0.4064)
			(end -0.7874 0.4064)
			(stroke
				(width 0.1524)
				(type default)
			)
			(layer "B.SilkS")
		)
		(fp_line
			(start 0.67945 0.3048)
			(end 0.67945 -0.305054)
			(stroke
				(width 0.1)
				(type default)
			)
			(layer "B.Fab")
		)
		(fp_line
			(start 0.67945 -0.305054)
			(end 0.12065 -0.305054)
			(stroke
				(width 0.1)
				(type default)
			)
			(layer "B.Fab")
		)
		(fp_line
			(start 0.12065 0.3048)
			(end 0.67945 0.3048)
			(stroke
				(width 0.1)
				(type default)
			)
			(layer "B.Fab")
		)
		(fp_line
			(start 0.12065 0.2794)
			(end 0.12065 0.3048)
			(stroke
				(width 0.1)
				(type default)
			)
			(layer "B.Fab")
		)
		(fp_line
			(start 0.12065 -0.2794)
			(end -0.12065 -0.2794)
			(stroke
				(width 0.1)
				(type default)
			)
			(layer "B.Fab")
		)
		(fp_line
			(start 0.12065 -0.305054)
			(end 0.12065 -0.2794)
			(stroke
				(width 0.1)
				(type default)
			)
			(layer "B.Fab")
		)
		(fp_line
			(start -0.120396 0.3048)
			(end -0.120396 0.2794)
			(stroke
				(width 0.1)
				(type default)
			)
			(layer "B.Fab")
		)
		(fp_line
			(start -0.120396 0.2794)
			(end 0.12065 0.2794)
			(stroke
				(width 0.1)
				(type default)
			)
			(layer "B.Fab")
		)
		(fp_line
			(start -0.12065 -0.2794)
			(end -0.12065 -0.3048)
			(stroke
				(width 0.1)
				(type default)
			)
			(layer "B.Fab")
		)
		(fp_line
			(start -0.12065 -0.3048)
			(end -0.67945 -0.3048)
			(stroke
				(width 0.1)
				(type default)
			)
			(layer "B.Fab")
		)
		(fp_line
			(start -0.67945 0.3048)
			(end -0.120396 0.3048)
			(stroke
				(width 0.1)
				(type default)
			)
			(layer "B.Fab")
		)
		(fp_line
			(start -0.67945 -0.3048)
			(end -0.67945 0.3048)
			(stroke
				(width 0.1)
				(type default)
			)
			(layer "B.Fab")
		)
		(pad "1" smd circle
			(at 0.40005 0)
			(size 0 0)
			(layers "B.Cu" "B.Mask" "B.Paste")
			(net "PVDD_33_S5_ADC")
		)
		(pad "2" smd circle
			(at -0.40005 0)
			(size 0 0)
			(layers "B.Cu" "B.Mask" "B.Paste")
			(net "GND")
		)
	)
	(footprint ""
		(layer "B.Cu")
		(at 94.30639 -386.766562 90)
		(property "Reference" "C314"
			(at 0 0 90)
			(layer "B.SilkS")
			(hide yes)
			(effects
				(font
					(size 1.27 1.27)
				)
				(justify mirror)
			)
		)
		(property "Value" ""
			(at 0 0 90)
			(layer "B.Fab")
			(effects
				(font
					(size 1.27 1.27)
				)
				(justify mirror)
			)
		)
		(duplicate_pad_numbers_are_jumpers no)
		(fp_line
			(start 0.299974 -0.150114)
			(end -0.299974 -0.150114)
			(stroke
				(width 0.1)
				(type default)
			)
			(layer "B.Fab")
		)
		(fp_line
			(start -0.299974 -0.150114)
			(end -0.299974 0.150114)
			(stroke
				(width 0.1)
				(type default)
			)
			(layer "B.Fab")
		)
		(fp_line
			(start 0.299974 0.150114)
			(end 0.299974 -0.150114)
			(stroke
				(width 0.1)
				(type default)
			)
			(layer "B.Fab")
		)
		(fp_line
			(start -0.299974 0.150114)
			(end 0.299974 0.150114)
			(stroke
				(width 0.1)
				(type default)
			)
			(layer "B.Fab")
		)
		(pad "1" smd rect
			(at 0.2667 0 270)
			(size 0.3048 0.381)
			(layers "B.Cu" "B.Mask" "B.Paste")
			(net "P0V9_CPU1_RT1_2A")
		)
		(pad "2" smd rect
			(at -0.2667 0 270)
			(size 0.3048 0.381)
			(layers "B.Cu" "B.Mask" "B.Paste")
			(net "GND")
		)
	)
)
